#ISCELL
  mstr_misc dns *
  *
#ISCELL
  mstr_symbols design_note *
  *
#ISCELL
  mstr_symbols intel_corp_bpage *
  *
#CELL
  mstr_discrete ir354xx *
  page212_i101
#ISCELL
  mstr_symbols gnd *
  page212_i102
#CELL
  mstr_discrete res *
  page212_i103
#CELL
  mstr_misc shunt *
  page212_i104
#CELL
  mstr_misc shunt *
  page212_i105
#CELL
  dev_discrete cap_a *
  page212_i106
#ISCELL
  mstr_symbols gnd *
  page212_i107
#CELL
  mstr_discrete cap *
  page212_i109
#ISCELL
  mstr_symbols gnd *
  page212_i110
#ISCELL
  mstr_symbols gnd *
  page212_i113
#CELL
  mstr_discrete cap *
  page212_i118
#CELL
  mstr_discrete res *
  page212_i120
#CELL
  w_hdl sc22u16v5mx-4-gp *
  page212_i124
#ISCELL
  mstr_symbols gnd *
  page212_i125
#CELL
  w_hdl sc22u16v5mx-4-gp *
  page212_i126
#ISCELL
  mstr_symbols gnd *
  page212_i127
#ISCELL
  mstr_symbols gnd *
  page212_i128
#CELL
  w_hdl sc22u16v5mx-4-gp *
  page212_i129
#ISCELL
  mstr_symbols gnd *
  page212_i13
#CELL
  w_hdl sc22u16v5mx-4-gp *
  page212_i130
#ISCELL
  mstr_symbols gnd *
  page212_i131
#CELL
  w_hdl sc22u16v5mx-4-gp *
  page212_i132
#ISCELL
  mstr_symbols gnd *
  page212_i133
#CELL
  w_hdl sc22u16v5mx-4-gp *
  page212_i134
#ISCELL
  mstr_symbols gnd *
  page212_i135
#CELL
  w_hdl sc22u16v5mx-4-gp *
  page212_i136
#ISCELL
  mstr_symbols gnd *
  page212_i137
#CELL
  w_hdl sc22u16v5mx-4-gp *
  page212_i138
#ISCELL
  mstr_symbols gnd *
  page212_i139
#CELL
  mstr_discrete res *
  page212_i140
#CELL
  w_hdl ind-150nh-56-gp *
  page212_i141
#CELL
  w_hdl ind-100nh-35-gp *
  page212_i142
#CELL
  w_hdl sc1u10v2kx-4-gp *
  page212_i143
#CELL
  w_hdl 1r3f-gp *
  page212_i144
#CELL
  mstr_discrete capp *
  page212_i145
#CELL
  mstr_discrete capp *
  page212_i146
#CELL
  mstr_discrete capp *
  page212_i18
#ISCELL
  mstr_standard offpage *
  page212_i19
#ISCELL
  mstr_standard offpage *
  page212_i20
#ISCELL
  mstr_standard offpage *
  page212_i21
#ISCELL
  mstr_symbols pvccio_cpu0 *
  page212_i22
#CELL
  dev_discrete cap_a *
  page212_i23
#ISCELL
  mstr_symbols gnd *
  page212_i24
#ISCELL
  mstr_symbols gnd *
  page212_i29
#CELL
  mstr_discrete cap *
  page212_i33
#CELL
  mstr_discrete cap *
  page212_i36
#CELL
  mstr_discrete cap *
  page212_i37
#CELL
  dev_discrete cap_a *
  page212_i38
#CELL
  mstr_discrete cap *
  page212_i39
#CELL
  mstr_discrete cap *
  page212_i40
#CELL
  mstr_discrete cap *
  page212_i41
#CELL
  mstr_discrete cap *
  page212_i43
#ISCELL
  mstr_symbols gnd *
  page212_i44
#ISCELL
  mstr_standard offpage *
  page212_i45
#ISCELL
  mstr_symbols p12v_stby *
  page212_i57
#ISCELL
  mstr_symbols p5v_stby *
  page212_i58
#ISCELL
  mstr_standard offpage *
  page212_i59
#CELL
  dev_discrete cap_a *
  page212_i60
#ISCELL
  mstr_standard offpage *
  page212_i61
#CELL
  mstr_discrete res *
  page212_i68
#ISCELL
  mstr_symbols gnd *
  page212_i69
#ISCELL
  mstr_standard offpage *
  page212_i70
#CELL
  mstr_discrete res *
  page212_i74
#ISCELL
  mstr_symbols pvccio_cpu0 *
  page212_i75
#ISCELL
  mstr_standard offpage *
  page212_i76
#CELL
  dev_discrete cap_a *
  page212_i77
#CELL
  mstr_discrete res *
  page212_i78
#ISCELL
  mstr_symbols vcc_core *
  page212_i79
#ISCELL
  mstr_symbols vcc_core *
  page212_i80
#ISCELL
  mstr_symbols pvccio_cpu0 *
  page212_i82
